(kicad_pcb
	(version 20260206)
	(generator "pcbnew")
	(generator_version "10.0")
	(general
		(thickness 1.6)
		(legacy_teardrops no)
	)
	(paper "A4")
	(title_block
		(title "pdpb — Lightning_PDPB_BRD.brd")
		(comment 1 "Lightning (Wiwynn / Facebook NVMe JBOF) / footprints 937-944 of 1140")
	)
	(layers
		(0 "F.Cu" signal "TOP")
		(4 "In1.Cu" signal "L2GND")
		(6 "In2.Cu" signal "L3")
		(8 "In3.Cu" signal "L4VCC")
		(10 "In4.Cu" signal "L5VCC")
		(12 "In5.Cu" signal "L6")
		(14 "In6.Cu" signal "L7GND")
		(2 "B.Cu" signal "BOTTOM")
		(9 "F.Adhes" user "F.Adhesive")
		(11 "B.Adhes" user "B.Adhesive")
		(13 "F.Paste" user "Package Geometry/Pastemask Top")
		(15 "B.Paste" user "Package Geometry/Pastemask Bottom")
		(5 "F.SilkS" user "Ref Des/Silkscreen Top")
		(7 "B.SilkS" user "Ref Des/Silkscreen Bottom")
		(1 "F.Mask" user "Board Geometry/Soldermask Top")
		(3 "B.Mask" user "Board Geometry/Soldermask Bottom")
		(17 "Dwgs.User" user "User.Drawings")
		(19 "Cmts.User" user "User.Comments")
		(21 "Eco1.User" user "User.Eco1")
		(23 "Eco2.User" user "User.Eco2")
		(25 "Edge.Cuts" user "Board Geometry/Outline")
		(27 "Margin" user)
		(31 "F.CrtYd" user "Package Geometry/Place Bound Top")
		(29 "B.CrtYd" user "Package Geometry/Place Bound Bottom")
		(35 "F.Fab" user "Ref Des/Assembly Top")
		(33 "B.Fab" user "Ref Des/Assembly Bottom")
	)
	(footprint ""
		(layer "F.Cu")
		(at 99.949 -211.201 180)
		(property "Reference" "C9516"
			(at 0 0 180)
			(layer "F.SilkS")
			(hide yes)
			(effects
				(font
					(size 1.27 1.27)
				)
			)
		)
		(property "Value" "SCD1U16V2KX-3GP"
			(at 1.1811 -2.7051 180)
			(unlocked yes)
			(layer "F.Fab")
			(hide yes)
			(effects
				(font
					(size 1.016 1.016)
					(thickness 0.1524)
				)
			)
		)
		(property "Device Type" "C402H22"
			(at 1.1811 -4.2291 180)
			(unlocked yes)
			(layer "F.Fab")
			(hide yes)
			(effects
				(font
					(size 1.016 1.016)
					(thickness 0.1524)
				)
			)
		)
		(duplicate_pad_numbers_are_jumpers no)
		(fp_rect
			(start -0.4318 0.9525)
			(end 0.4318 -0.9525)
			(stroke
				(width 0)
				(type default)
			)
			(fill no)
			(layer "F.CrtYd")
		)
		(fp_rect
			(start -0.4318 0.9525)
			(end 0.4318 -0.9525)
			(stroke
				(width 0)
				(type default)
			)
			(fill no)
			(layer "F.Fab")
		)
		(pad "1" smd custom
			(at 0 -0.4445 180)
			(size 0.1524 0.1524)
			(layers "F.Cu" "F.Mask" "F.Paste")
			(net "VDD_DIFF_3")
			(options
				(clearance outline)
				(anchor circle)
			)
			(primitives
				(gr_poly
					(pts
						(arc
							(start 0.3048 -0.2032)
							(mid 0.275042 -0.275042)
							(end 0.2032 -0.3048)
						)
						(arc
							(start -0.2032 -0.3048)
							(mid -0.275042 -0.275042)
							(end -0.3048 -0.2032)
						)
						(arc
							(start -0.3048 0.2032)
							(mid -0.275042 0.275042)
							(end -0.2032 0.3048)
						)
						(arc
							(start 0.2032 0.3048)
							(mid 0.275042 0.275042)
							(end 0.3048 0.2032)
						)
					)
					(width 0)
					(fill yes)
				)
			)
		)
		(pad "2" smd custom
			(at 0 0.4445 180)
			(size 0.1524 0.1524)
			(layers "F.Cu" "F.Mask" "F.Paste")
			(net "GND")
			(options
				(clearance outline)
				(anchor circle)
			)
			(primitives
				(gr_poly
					(pts
						(arc
							(start 0.3048 -0.2032)
							(mid 0.275042 -0.275042)
							(end 0.2032 -0.3048)
						)
						(arc
							(start -0.2032 -0.3048)
							(mid -0.275042 -0.275042)
							(end -0.3048 -0.2032)
						)
						(arc
							(start -0.3048 0.2032)
							(mid -0.275042 0.275042)
							(end -0.2032 0.3048)
						)
						(arc
							(start 0.2032 0.3048)
							(mid 0.275042 0.275042)
							(end 0.3048 0.2032)
						)
					)
					(width 0)
					(fill yes)
				)
			)
		)
	)
	(footprint ""
		(layer "F.Cu")
		(at 206.883 -435.483 90)
		(property "Reference" "PR9088"
			(at 0 0 90)
			(layer "F.SilkS")
			(hide yes)
			(effects
				(font
					(size 1.27 1.27)
				)
			)
		)
		(property "Value" "0R6J-3-GP"
			(at -0.0508 -4.8514 90)
			(unlocked yes)
			(layer "F.Fab")
			(hide yes)
			(effects
				(font
					(size 1.016 1.016)
					(thickness 0.1524)
				)
			)
		)
		(property "Device Type" "R1206H28"
			(at 0 -6.3754 90)
			(unlocked yes)
			(layer "F.Fab")
			(hide yes)
			(effects
				(font
					(size 1.016 1.016)
					(thickness 0.1524)
				)
			)
		)
		(duplicate_pad_numbers_are_jumpers no)
		(fp_line
			(start 1.016 -2.2352)
			(end 1.016 2.2352)
			(stroke
				(width 0.1524)
				(type default)
			)
			(layer "F.SilkS")
		)
		(fp_line
			(start -1.016 -2.2352)
			(end 1.016 -2.2352)
			(stroke
				(width 0.1524)
				(type default)
			)
			(layer "F.SilkS")
		)
		(fp_line
			(start 1.016 2.2352)
			(end -1.016 2.2352)
			(stroke
				(width 0.1524)
				(type default)
			)
			(layer "F.SilkS")
		)
		(fp_line
			(start -1.016 2.2352)
			(end -1.016 -2.2352)
			(stroke
				(width 0.1524)
				(type default)
			)
			(layer "F.SilkS")
		)
		(fp_rect
			(start -1.0922 2.3114)
			(end 1.0922 -2.3114)
			(stroke
				(width 0)
				(type default)
			)
			(fill no)
			(layer "F.CrtYd")
		)
		(fp_poly
			(pts
				(xy -1.0922 -2.3114) (xy 1.0922 -2.3114) (xy 1.0922 2.3114) (xy -1.0922 2.3114)
			)
			(stroke
				(width 0)
				(type default)
			)
			(fill no)
			(layer "F.Fab")
		)
		(pad "1" smd rect
			(at 0 -1.397 90)
			(size 1.651 1.27)
			(layers "F.Cu" "F.Mask" "F.Paste")
			(net "P3V3")
		)
		(pad "2" smd rect
			(at 0 1.397 90)
			(size 1.651 1.27)
			(layers "F.Cu" "F.Mask" "F.Paste")
			(net "P3V3_OUT")
		)
	)
	(footprint ""
		(layer "F.Cu")
		(at 19.4945 -162.073336 180)
		(property "Reference" "R9869"
			(at 0 0 180)
			(layer "F.SilkS")
			(hide yes)
			(effects
				(font
					(size 1.27 1.27)
				)
			)
		)
		(property "Value" "0R2J-2-GP"
			(at 0.064008 -3.993896 180)
			(unlocked yes)
			(layer "F.Fab")
			(hide yes)
			(effects
				(font
					(size 1.016 1.016)
					(thickness 0.1524)
				)
			)
		)
		(property "Device Type" "R402H16"
			(at 0.064008 -5.517896 180)
			(unlocked yes)
			(layer "F.Fab")
			(hide yes)
			(effects
				(font
					(size 1.016 1.016)
					(thickness 0.1524)
				)
			)
		)
		(duplicate_pad_numbers_are_jumpers no)
		(fp_line
			(start 0.508 -0.9398)
			(end -0.508 -0.9398)
			(stroke
				(width 0.1524)
				(type default)
			)
			(layer "F.SilkS")
		)
		(fp_line
			(start -0.508 -0.9398)
			(end -0.508 0.9398)
			(stroke
				(width 0.1524)
				(type default)
			)
			(layer "F.SilkS")
		)
		(fp_rect
			(start -0.508 0.9398)
			(end 0.508 -0.9398)
			(stroke
				(width 0)
				(type default)
			)
			(fill no)
			(layer "F.CrtYd")
		)
		(fp_rect
			(start -0.508 0.9398)
			(end 0.508 -0.9398)
			(stroke
				(width 0)
				(type default)
			)
			(fill no)
			(layer "F.Fab")
		)
		(pad "1" smd custom
			(at 0 -0.4445 180)
			(size 0.1397 0.1397)
			(layers "F.Cu" "F.Mask" "F.Paste")
			(net "SSD_ACT_DR13_R")
			(options
				(clearance outline)
				(anchor circle)
			)
			(primitives
				(gr_poly
					(pts
						(arc
							(start -0.1778 -0.2794)
							(mid -0.249642 -0.249642)
							(end -0.2794 -0.1778)
						)
						(arc
							(start -0.2794 0.1778)
							(mid -0.249642 0.249642)
							(end -0.1778 0.2794)
						)
						(arc
							(start 0.1778 0.2794)
							(mid 0.249642 0.249642)
							(end 0.2794 0.1778)
						)
						(arc
							(start 0.2794 -0.1778)
							(mid 0.249642 -0.249642)
							(end 0.1778 -0.2794)
						)
					)
					(width 0)
					(fill yes)
				)
			)
		)
		(pad "2" smd custom
			(at 0 0.4445 180)
			(size 0.1397 0.1397)
			(layers "F.Cu" "F.Mask" "F.Paste")
			(net "SSD_ACT_DR13")
			(options
				(clearance outline)
				(anchor circle)
			)
			(primitives
				(gr_poly
					(pts
						(arc
							(start -0.1778 -0.2794)
							(mid -0.249642 -0.249642)
							(end -0.2794 -0.1778)
						)
						(arc
							(start -0.2794 0.1778)
							(mid -0.249642 0.249642)
							(end -0.1778 0.2794)
						)
						(arc
							(start 0.1778 0.2794)
							(mid 0.249642 0.249642)
							(end 0.2794 0.1778)
						)
						(arc
							(start 0.2794 -0.1778)
							(mid 0.249642 -0.249642)
							(end 0.1778 -0.2794)
						)
					)
					(width 0)
					(fill yes)
				)
			)
		)
	)
	(footprint ""
		(layer "F.Cu")
		(at 8.3439 -384.0988 180)
		(property "Reference" "C9537"
			(at 0 0 180)
			(layer "F.SilkS")
			(hide yes)
			(effects
				(font
					(size 1.27 1.27)
				)
			)
		)
		(property "Value" "SCD01U50V2KX-1GP"
			(at 1.1811 -2.7051 180)
			(unlocked yes)
			(layer "F.Fab")
			(hide yes)
			(effects
				(font
					(size 1.016 1.016)
					(thickness 0.1524)
				)
			)
		)
		(property "Device Type" "C402H22"
			(at 1.1811 -4.2291 180)
			(unlocked yes)
			(layer "F.Fab")
			(hide yes)
			(effects
				(font
					(size 1.016 1.016)
					(thickness 0.1524)
				)
			)
		)
		(duplicate_pad_numbers_are_jumpers no)
		(fp_rect
			(start -0.4318 0.9525)
			(end 0.4318 -0.9525)
			(stroke
				(width 0)
				(type default)
			)
			(fill no)
			(layer "F.CrtYd")
		)
		(fp_rect
			(start -0.4318 0.9525)
			(end 0.4318 -0.9525)
			(stroke
				(width 0)
				(type default)
			)
			(fill no)
			(layer "F.Fab")
		)
		(pad "1" smd custom
			(at 0 -0.4445 180)
			(size 0.1524 0.1524)
			(layers "F.Cu" "F.Mask" "F.Paste")
			(net "PE_100M_CLK2_N")
			(options
				(clearance outline)
				(anchor circle)
			)
			(primitives
				(gr_poly
					(pts
						(arc
							(start 0.3048 -0.2032)
							(mid 0.275042 -0.275042)
							(end 0.2032 -0.3048)
						)
						(arc
							(start -0.2032 -0.3048)
							(mid -0.275042 -0.275042)
							(end -0.3048 -0.2032)
						)
						(arc
							(start -0.3048 0.2032)
							(mid -0.275042 0.275042)
							(end -0.2032 0.3048)
						)
						(arc
							(start 0.2032 0.3048)
							(mid 0.275042 0.275042)
							(end 0.3048 0.2032)
						)
					)
					(width 0)
					(fill yes)
				)
			)
		)
		(pad "2" smd custom
			(at 0 0.4445 180)
			(size 0.1524 0.1524)
			(layers "F.Cu" "F.Mask" "F.Paste")
			(net "PE_100M_CLK2_C_N")
			(options
				(clearance outline)
				(anchor circle)
			)
			(primitives
				(gr_poly
					(pts
						(arc
							(start 0.3048 -0.2032)
							(mid 0.275042 -0.275042)
							(end 0.2032 -0.3048)
						)
						(arc
							(start -0.2032 -0.3048)
							(mid -0.275042 -0.275042)
							(end -0.3048 -0.2032)
						)
						(arc
							(start -0.3048 0.2032)
							(mid -0.275042 0.275042)
							(end -0.2032 0.3048)
						)
						(arc
							(start 0.2032 0.3048)
							(mid 0.275042 0.275042)
							(end 0.3048 0.2032)
						)
					)
					(width 0)
					(fill yes)
				)
			)
		)
	)
	(footprint ""
		(layer "F.Cu")
		(at 51.562 -134.493)
		(property "Reference" "R353"
			(at 0 0 0)
			(layer "F.SilkS")
			(hide yes)
			(effects
				(font
					(size 1.27 1.27)
				)
			)
		)
		(property "Value" "4K7R2F-GP"
			(at 0.064008 -3.993896 0)
			(unlocked yes)
			(layer "F.Fab")
			(hide yes)
			(effects
				(font
					(size 1.016 1.016)
					(thickness 0.1524)
				)
			)
		)
		(property "Device Type" "R402H16"
			(at 0.064008 -5.517896 0)
			(unlocked yes)
			(layer "F.Fab")
			(hide yes)
			(effects
				(font
					(size 1.016 1.016)
					(thickness 0.1524)
				)
			)
		)
		(duplicate_pad_numbers_are_jumpers no)
		(fp_line
			(start -0.508 -0.9398)
			(end -0.508 0.9398)
			(stroke
				(width 0.1524)
				(type default)
			)
			(layer "F.SilkS")
		)
		(fp_line
			(start 0.508 -0.9398)
			(end -0.508 -0.9398)
			(stroke
				(width 0.1524)
				(type default)
			)
			(layer "F.SilkS")
		)
		(fp_rect
			(start -0.508 0.9398)
			(end 0.508 -0.9398)
			(stroke
				(width 0)
				(type default)
			)
			(fill no)
			(layer "F.CrtYd")
		)
		(fp_rect
			(start -0.508 0.9398)
			(end 0.508 -0.9398)
			(stroke
				(width 0)
				(type default)
			)
			(fill no)
			(layer "F.Fab")
		)
		(pad "1" smd custom
			(at 0 -0.4445)
			(size 0.1397 0.1397)
			(layers "F.Cu" "F.Mask" "F.Paste")
			(net "P3V3")
			(options
				(clearance outline)
				(anchor circle)
			)
			(primitives
				(gr_poly
					(pts
						(arc
							(start -0.1778 -0.2794)
							(mid -0.249642 -0.249642)
							(end -0.2794 -0.1778)
						)
						(arc
							(start -0.2794 0.1778)
							(mid -0.249642 0.249642)
							(end -0.1778 0.2794)
						)
						(arc
							(start 0.1778 0.2794)
							(mid 0.249642 0.249642)
							(end 0.2794 0.1778)
						)
						(arc
							(start 0.2794 -0.1778)
							(mid 0.249642 -0.249642)
							(end 0.1778 -0.2794)
						)
					)
					(width 0)
					(fill yes)
				)
			)
		)
		(pad "2" smd custom
			(at 0 0.4445)
			(size 0.1397 0.1397)
			(layers "F.Cu" "F.Mask" "F.Paste")
			(net "I2C_B_TMP1_A2")
			(options
				(clearance outline)
				(anchor circle)
			)
			(primitives
				(gr_poly
					(pts
						(arc
							(start -0.1778 -0.2794)
							(mid -0.249642 -0.249642)
							(end -0.2794 -0.1778)
						)
						(arc
							(start -0.2794 0.1778)
							(mid -0.249642 0.249642)
							(end -0.1778 0.2794)
						)
						(arc
							(start 0.1778 0.2794)
							(mid 0.249642 0.249642)
							(end 0.2794 0.1778)
						)
						(arc
							(start 0.2794 -0.1778)
							(mid 0.249642 -0.249642)
							(end 0.1778 -0.2794)
						)
					)
					(width 0)
					(fill yes)
				)
			)
		)
	)
	(footprint ""
		(layer "F.Cu")
		(at 20.828 -62.353952 180)
		(property "Reference" "C9532"
			(at 0 0 180)
			(layer "F.SilkS")
			(hide yes)
			(effects
				(font
					(size 1.27 1.27)
				)
			)
		)
		(property "Value" "SCD1U16V2KX-3GP"
			(at 1.1811 -2.7051 180)
			(unlocked yes)
			(layer "F.Fab")
			(hide yes)
			(effects
				(font
					(size 1.016 1.016)
					(thickness 0.1524)
				)
			)
		)
		(property "Device Type" "C402H22"
			(at 1.1811 -4.2291 180)
			(unlocked yes)
			(layer "F.Fab")
			(hide yes)
			(effects
				(font
					(size 1.016 1.016)
					(thickness 0.1524)
				)
			)
		)
		(duplicate_pad_numbers_are_jumpers no)
		(fp_rect
			(start -0.4318 0.9525)
			(end 0.4318 -0.9525)
			(stroke
				(width 0)
				(type default)
			)
			(fill no)
			(layer "F.CrtYd")
		)
		(fp_rect
			(start -0.4318 0.9525)
			(end 0.4318 -0.9525)
			(stroke
				(width 0)
				(type default)
			)
			(fill no)
			(layer "F.Fab")
		)
		(pad "1" smd custom
			(at 0 -0.4445 180)
			(size 0.1524 0.1524)
			(layers "F.Cu" "F.Mask" "F.Paste")
			(net "P3V3")
			(options
				(clearance outline)
				(anchor circle)
			)
			(primitives
				(gr_poly
					(pts
						(arc
							(start 0.3048 -0.2032)
							(mid 0.275042 -0.275042)
							(end 0.2032 -0.3048)
						)
						(arc
							(start -0.2032 -0.3048)
							(mid -0.275042 -0.275042)
							(end -0.3048 -0.2032)
						)
						(arc
							(start -0.3048 0.2032)
							(mid -0.275042 0.275042)
							(end -0.2032 0.3048)
						)
						(arc
							(start 0.2032 0.3048)
							(mid 0.275042 0.275042)
							(end 0.3048 0.2032)
						)
					)
					(width 0)
					(fill yes)
				)
			)
		)
		(pad "2" smd custom
			(at 0 0.4445 180)
			(size 0.1524 0.1524)
			(layers "F.Cu" "F.Mask" "F.Paste")
			(net "GND")
			(options
				(clearance outline)
				(anchor circle)
			)
			(primitives
				(gr_poly
					(pts
						(arc
							(start 0.3048 -0.2032)
							(mid 0.275042 -0.275042)
							(end 0.2032 -0.3048)
						)
						(arc
							(start -0.2032 -0.3048)
							(mid -0.275042 -0.275042)
							(end -0.3048 -0.2032)
						)
						(arc
							(start -0.3048 0.2032)
							(mid -0.275042 0.275042)
							(end -0.2032 0.3048)
						)
						(arc
							(start 0.2032 0.3048)
							(mid 0.275042 0.275042)
							(end 0.3048 0.2032)
						)
					)
					(width 0)
					(fill yes)
				)
			)
		)
	)
	(footprint ""
		(layer "F.Cu")
		(at 227.203 -343.912952 90)
		(property "Reference" "U198"
			(at 0 0 90)
			(layer "F.SilkS")
			(hide yes)
			(effects
				(font
					(size 1.27 1.27)
				)
			)
		)
		(property "Value" "SN74LVC1G08DCKR-GP"
			(at -2.3368 -8.6868 90)
			(unlocked yes)
			(layer "F.Fab")
			(hide yes)
			(effects
				(font
					(size 1.016 1.016)
					(thickness 0.1524)
				)
			)
		)
		(property "Device Type" "SC70-5H44"
			(at -2.3114 -10.414 90)
			(unlocked yes)
			(layer "F.Fab")
			(hide yes)
			(effects
				(font
					(size 1.016 1.016)
					(thickness 0.1524)
				)
			)
		)
		(duplicate_pad_numbers_are_jumpers no)
		(fp_line
			(start 1.3843 -1.8034)
			(end 1.3843 -1.1176)
			(stroke
				(width 0.3302)
				(type default)
			)
			(layer "F.SilkS")
		)
		(fp_line
			(start 0.6604 -1.8034)
			(end 1.3843 -1.8034)
			(stroke
				(width 0.3302)
				(type default)
			)
			(layer "F.SilkS")
		)
		(fp_line
			(start 1.27 -1.7018)
			(end 1.27 1.7018)
			(stroke
				(width 0.1524)
				(type default)
			)
			(layer "F.SilkS")
		)
		(fp_line
			(start -1.27 -1.7018)
			(end 1.27 -1.7018)
			(stroke
				(width 0.1524)
				(type default)
			)
			(layer "F.SilkS")
		)
		(fp_line
			(start 1.27 1.7018)
			(end -1.27 1.7018)
			(stroke
				(width 0.1524)
				(type default)
			)
			(layer "F.SilkS")
		)
		(fp_line
			(start -1.27 1.7018)
			(end -1.27 -1.7018)
			(stroke
				(width 0.1524)
				(type default)
			)
			(layer "F.SilkS")
		)
		(fp_rect
			(start -1.524 1.9558)
			(end 1.524 -1.9558)
			(stroke
				(width 0)
				(type default)
			)
			(fill no)
			(layer "F.CrtYd")
		)
		(fp_poly
			(pts
				(xy -1.524 -1.9558) (xy 1.524 -1.9558) (xy 1.524 1.9558) (xy -1.524 1.9558)
			)
			(stroke
				(width 0)
				(type default)
			)
			(fill no)
			(layer "F.Fab")
		)
		(pad "1" smd rect
			(at 0.65024 -0.8255 90)
			(size 0.4064 1.2192)
			(layers "F.Cu" "F.Mask" "F.Paste")
			(net "SSD1_CLK0_OE_MOS_N")
		)
		(pad "2" smd rect
			(at 0 -0.8255 90)
			(size 0.4064 1.2192)
			(layers "F.Cu" "F.Mask" "F.Paste")
			(net "ATTN_LED_DR1_N")
		)
		(pad "3" smd rect
			(at -0.65024 -0.8255 90)
			(size 0.4064 1.2192)
			(layers "F.Cu" "F.Mask" "F.Paste")
			(net "GND")
		)
		(pad "4" smd rect
			(at -0.65024 0.8255 90)
			(size 0.4064 1.2192)
			(layers "F.Cu" "F.Mask" "F.Paste")
			(net "ATTN_LED_DR1_AND")
		)
		(pad "5" smd rect
			(at 0.65024 0.8255 90)
			(size 0.4064 1.2192)
			(layers "F.Cu" "F.Mask" "F.Paste")
			(net "P3V3")
		)
	)
	(footprint ""
		(layer "F.Cu")
		(at 70.739 -148.59 90)
		(property "Reference" "SR968"
			(at 0 0 90)
			(layer "F.SilkS")
			(hide yes)
			(effects
				(font
					(size 1.27 1.27)
				)
			)
		)
		(property "Value" "2KR2F-3-GP"
			(at 0.064008 -3.993896 90)
			(unlocked yes)
			(layer "F.Fab")
			(hide yes)
			(effects
				(font
					(size 1.016 1.016)
					(thickness 0.1524)
				)
			)
		)
		(property "Device Type" "R402H16"
			(at 0.064008 -5.517896 90)
			(unlocked yes)
			(layer "F.Fab")
			(hide yes)
			(effects
				(font
					(size 1.016 1.016)
					(thickness 0.1524)
				)
			)
		)
		(duplicate_pad_numbers_are_jumpers no)
		(fp_line
			(start 0.508 -0.9398)
			(end -0.508 -0.9398)
			(stroke
				(width 0.1524)
				(type default)
			)
			(layer "F.SilkS")
		)
		(fp_line
			(start -0.508 -0.9398)
			(end -0.508 0.9398)
			(stroke
				(width 0.1524)
				(type default)
			)
			(layer "F.SilkS")
		)
		(fp_rect
			(start -0.508 0.9398)
			(end 0.508 -0.9398)
			(stroke
				(width 0)
				(type default)
			)
			(fill no)
			(layer "F.CrtYd")
		)
		(fp_rect
			(start -0.508 0.9398)
			(end 0.508 -0.9398)
			(stroke
				(width 0)
				(type default)
			)
			(fill no)
			(layer "F.Fab")
		)
		(pad "1" smd custom
			(at 0 -0.4445 90)
			(size 0.1397 0.1397)
			(layers "F.Cu" "F.Mask" "F.Paste")
			(net "P3V3")
			(options
				(clearance outline)
				(anchor circle)
			)
			(primitives
				(gr_poly
					(pts
						(arc
							(start -0.1778 -0.2794)
							(mid -0.249642 -0.249642)
							(end -0.2794 -0.1778)
						)
						(arc
							(start -0.2794 0.1778)
							(mid -0.249642 0.249642)
							(end -0.1778 0.2794)
						)
						(arc
							(start 0.1778 0.2794)
							(mid 0.249642 0.249642)
							(end 0.2794 0.1778)
						)
						(arc
							(start 0.2794 -0.1778)
							(mid 0.249642 -0.249642)
							(end 0.1778 -0.2794)
						)
					)
					(width 0)
					(fill yes)
				)
			)
		)
		(pad "2" smd custom
			(at 0 0.4445 90)
			(size 0.1397 0.1397)
			(layers "F.Cu" "F.Mask" "F.Paste")
			(net "SDA_DR13")
			(options
				(clearance outline)
				(anchor circle)
			)
			(primitives
				(gr_poly
					(pts
						(arc
							(start -0.1778 -0.2794)
							(mid -0.249642 -0.249642)
							(end -0.2794 -0.1778)
						)
						(arc
							(start -0.2794 0.1778)
							(mid -0.249642 0.249642)
							(end -0.1778 0.2794)
						)
						(arc
							(start 0.1778 0.2794)
							(mid 0.249642 0.249642)
							(end 0.2794 0.1778)
						)
						(arc
							(start 0.2794 -0.1778)
							(mid 0.249642 -0.249642)
							(end 0.1778 -0.2794)
						)
					)
					(width 0)
					(fill yes)
				)
			)
		)
	)
)
